(kicad_pcb
	(version 20241229)
	(generator "pcbnew")
	(generator_version "9.0")
	(general
		(thickness 1.61)
		(legacy_teardrops no)
	)
	(paper "A3")
	(title_block
		(title "RDIMM DDR5 Tester")
		(date "2026-05-21")
		(rev "2.2.0")
		(company "Antmicro")
		(comment 9 "footprints 32-36 of 796")
	)
	(layers
		(0 "F.Cu" signal)
		(4 "In1.Cu" power)
		(6 "In2.Cu" mixed)
		(8 "In3.Cu" power)
		(10 "In4.Cu" mixed)
		(12 "In5.Cu" power)
		(14 "In6.Cu" mixed)
		(16 "In7.Cu" power)
		(18 "In8.Cu" power)
		(20 "In9.Cu" mixed)
		(22 "In10.Cu" power)
		(2 "B.Cu" signal)
		(9 "F.Adhes" user "F.Adhesive")
		(11 "B.Adhes" user "B.Adhesive")
		(13 "F.Paste" user)
		(15 "B.Paste" user)
		(5 "F.SilkS" user "F.Silkscreen")
		(7 "B.SilkS" user "B.Silkscreen")
		(1 "F.Mask" user)
		(3 "B.Mask" user)
		(17 "Dwgs.User" user "User.Drawings")
		(19 "Cmts.User" user "User.Comments")
		(21 "Eco1.User" user "User.Eco1")
		(23 "Eco2.User" user "User.Eco2")
		(25 "Edge.Cuts" user)
		(27 "Margin" user)
		(31 "F.CrtYd" user "F.Courtyard")
		(29 "B.CrtYd" user "B.Courtyard")
		(35 "F.Fab" user)
		(33 "B.Fab" user)
	)
	(footprint "antmicro-footprints:C_0402_1005Metric"
		(layer "F.Cu")
		(at 129.625 146.03 -90)
		(descr "Capacitor SMD 0402")
		(tags "capacitor SMD 0402")
		(property "Reference" "C150"
			(at 1.017149 -0.4 90)
			(layer "F.SilkS")
			(effects
				(font
					(size 0.7 0.7)
					(thickness 0.15)
				)
				(justify right bottom)
			)
		)
		(property "Value" "C_10n_0402"
			(at -1.022927 2.155213 90)
			(layer "F.Fab")
			(effects
				(font
					(size 0.7 0.7)
					(thickness 0.15)
				)
				(justify right bottom)
			)
		)
		(property "Datasheet" "https://www.murata.com/products/productdetail?partno=GRM155R71H103KA88%23"
			(at 0 0 270)
			(layer "F.Fab")
			(hide yes)
			(effects
				(font
					(size 1.27 1.27)
					(thickness 0.15)
				)
			)
		)
		(property "Manufacturer" "Murata"
			(at 0 0 270)
			(unlocked yes)
			(layer "F.Fab")
			(hide yes)
			(effects
				(font
					(size 1 1)
					(thickness 0.15)
				)
			)
		)
		(property "MPN" "GRM155R71H103KA88D"
			(at 0 0 270)
			(unlocked yes)
			(layer "F.Fab")
			(hide yes)
			(effects
				(font
					(size 1 1)
					(thickness 0.15)
				)
			)
		)
		(property "Val" "10n"
			(at 0 0 270)
			(unlocked yes)
			(layer "F.Fab")
			(hide yes)
			(effects
				(font
					(size 1 1)
					(thickness 0.15)
				)
			)
		)
		(property "License" "Apache-2.0"
			(at 0 0 270)
			(unlocked yes)
			(layer "F.Fab")
			(hide yes)
			(effects
				(font
					(size 1 1)
					(thickness 0.15)
				)
			)
		)
		(property "Author" "Antmicro"
			(at 0 0 270)
			(unlocked yes)
			(layer "F.Fab")
			(hide yes)
			(effects
				(font
					(size 1 1)
					(thickness 0.15)
				)
			)
		)
		(property "Voltage" "50V"
			(at 0 0 270)
			(unlocked yes)
			(layer "F.Fab")
			(hide yes)
			(effects
				(font
					(size 1 1)
					(thickness 0.15)
				)
			)
		)
		(property "Dielectric" "X7R"
			(at 0 0 270)
			(unlocked yes)
			(layer "F.Fab")
			(hide yes)
			(effects
				(font
					(size 1 1)
					(thickness 0.15)
				)
			)
		)
		(sheetname "/Ethernet/")
		(sheetfile "ethernet.kicad_sch")
		(attr smd)
		(fp_rect
			(start -0.925 -0.47)
			(end 0.925 0.47)
			(stroke
				(width 0.05)
				(type default)
			)
			(fill no)
			(layer "F.CrtYd")
		)
		(fp_line
			(start -0.494 0.248)
			(end -0.494 -0.25)
			(stroke
				(width 0.15)
				(type solid)
			)
			(layer "F.Fab")
		)
		(fp_line
			(start 0.504 0.248)
			(end -0.494 0.248)
			(stroke
				(width 0.15)
				(type solid)
			)
			(layer "F.Fab")
		)
		(fp_line
			(start -0.494 -0.25)
			(end 0.504 -0.25)
			(stroke
				(width 0.15)
				(type solid)
			)
			(layer "F.Fab")
		)
		(fp_line
			(start 0.504 -0.25)
			(end 0.504 0.248)
			(stroke
				(width 0.15)
				(type solid)
			)
			(layer "F.Fab")
		)
		(fp_text user "License: Apache-2.0"
			(at -0.939 5.799 270)
			(layer "F.Fab")
			(effects
				(font
					(size 0.7 0.7)
					(thickness 0.15)
				)
				(justify left bottom)
			)
		)
		(fp_text user "${REFERENCE}"
			(at -0.939 4.599 270)
			(layer "F.Fab")
			(effects
				(font
					(size 0.7 0.7)
					(thickness 0.15)
				)
				(justify left bottom)
			)
		)
		(fp_text user "Author: Antmicro"
			(at -0.939 3.399 270)
			(layer "F.Fab")
			(effects
				(font
					(size 0.7 0.7)
					(thickness 0.15)
				)
				(justify left bottom)
			)
		)
		(pad "1" smd roundrect
			(at -0.48 0 270)
			(size 0.59 0.64)
			(layers "F.Cu" "F.Mask" "F.Paste")
			(roundrect_rratio 0.25)
			(net 150 "+1V2")
			(pintype "passive")
		)
		(pad "2" smd roundrect
			(at 0.48 0 270)
			(size 0.59 0.64)
			(layers "F.Cu" "F.Mask" "F.Paste")
			(roundrect_rratio 0.25)
			(net 1 "GND")
			(pintype "passive")
		)
	)
	(footprint "antmicro-footprints:C_0402_1005Metric"
		(layer "F.Cu")
		(at 128.525 142.507851 -90)
		(descr "Capacitor SMD 0402")
		(tags "capacitor SMD 0402")
		(property "Reference" "C147"
			(at -0.982851 1.6 90)
			(layer "F.SilkS")
			(effects
				(font
					(size 0.7 0.7)
					(thickness 0.15)
				)
				(justify right bottom)
			)
		)
		(property "Value" "C_10n_0402"
			(at -1.022927 2.155213 90)
			(layer "F.Fab")
			(effects
				(font
					(size 0.7 0.7)
					(thickness 0.15)
				)
				(justify right bottom)
			)
		)
		(property "Datasheet" "https://www.murata.com/products/productdetail?partno=GRM155R71H103KA88%23"
			(at 0 0 270)
			(layer "F.Fab")
			(hide yes)
			(effects
				(font
					(size 1.27 1.27)
					(thickness 0.15)
				)
			)
		)
		(property "Manufacturer" "Murata"
			(at 0 0 270)
			(unlocked yes)
			(layer "F.Fab")
			(hide yes)
			(effects
				(font
					(size 1 1)
					(thickness 0.15)
				)
			)
		)
		(property "MPN" "GRM155R71H103KA88D"
			(at 0 0 270)
			(unlocked yes)
			(layer "F.Fab")
			(hide yes)
			(effects
				(font
					(size 1 1)
					(thickness 0.15)
				)
			)
		)
		(property "Val" "10n"
			(at 0 0 270)
			(unlocked yes)
			(layer "F.Fab")
			(hide yes)
			(effects
				(font
					(size 1 1)
					(thickness 0.15)
				)
			)
		)
		(property "License" "Apache-2.0"
			(at 0 0 270)
			(unlocked yes)
			(layer "F.Fab")
			(hide yes)
			(effects
				(font
					(size 1 1)
					(thickness 0.15)
				)
			)
		)
		(property "Author" "Antmicro"
			(at 0 0 270)
			(unlocked yes)
			(layer "F.Fab")
			(hide yes)
			(effects
				(font
					(size 1 1)
					(thickness 0.15)
				)
			)
		)
		(property "Voltage" "50V"
			(at 0 0 270)
			(unlocked yes)
			(layer "F.Fab")
			(hide yes)
			(effects
				(font
					(size 1 1)
					(thickness 0.15)
				)
			)
		)
		(property "Dielectric" "X7R"
			(at 0 0 270)
			(unlocked yes)
			(layer "F.Fab")
			(hide yes)
			(effects
				(font
					(size 1 1)
					(thickness 0.15)
				)
			)
		)
		(sheetname "/Ethernet/")
		(sheetfile "ethernet.kicad_sch")
		(attr smd)
		(fp_rect
			(start -0.925 -0.47)
			(end 0.925 0.47)
			(stroke
				(width 0.05)
				(type default)
			)
			(fill no)
			(layer "F.CrtYd")
		)
		(fp_line
			(start -0.494 0.248)
			(end -0.494 -0.25)
			(stroke
				(width 0.15)
				(type solid)
			)
			(layer "F.Fab")
		)
		(fp_line
			(start 0.504 0.248)
			(end -0.494 0.248)
			(stroke
				(width 0.15)
				(type solid)
			)
			(layer "F.Fab")
		)
		(fp_line
			(start -0.494 -0.25)
			(end 0.504 -0.25)
			(stroke
				(width 0.15)
				(type solid)
			)
			(layer "F.Fab")
		)
		(fp_line
			(start 0.504 -0.25)
			(end 0.504 0.248)
			(stroke
				(width 0.15)
				(type solid)
			)
			(layer "F.Fab")
		)
		(fp_text user "${REFERENCE}"
			(at -0.939 4.599 270)
			(layer "F.Fab")
			(effects
				(font
					(size 0.7 0.7)
					(thickness 0.15)
				)
				(justify left bottom)
			)
		)
		(fp_text user "Author: Antmicro"
			(at -0.939 3.399 270)
			(layer "F.Fab")
			(effects
				(font
					(size 0.7 0.7)
					(thickness 0.15)
				)
				(justify left bottom)
			)
		)
		(fp_text user "License: Apache-2.0"
			(at -0.939 5.799 270)
			(layer "F.Fab")
			(effects
				(font
					(size 0.7 0.7)
					(thickness 0.15)
				)
				(justify left bottom)
			)
		)
		(pad "1" smd roundrect
			(at -0.48 0 270)
			(size 0.59 0.64)
			(layers "F.Cu" "F.Mask" "F.Paste")
			(roundrect_rratio 0.25)
			(net 797 "+1V8")
			(pintype "passive")
		)
		(pad "2" smd roundrect
			(at 0.48 0 270)
			(size 0.59 0.64)
			(layers "F.Cu" "F.Mask" "F.Paste")
			(roundrect_rratio 0.25)
			(net 1 "GND")
			(pintype "passive")
		)
	)
	(footprint "antmicro-footprints:C_0402_1005Metric"
		(layer "F.Cu")
		(at 143.925 143.407851 180)
		(descr "Capacitor SMD 0402")
		(tags "capacitor SMD 0402")
		(property "Reference" "C163"
			(at -3.9 -0.442149 0)
			(layer "F.SilkS")
			(effects
				(font
					(size 0.7 0.7)
					(thickness 0.15)
				)
				(justify right bottom)
			)
		)
		(property "Value" "C_18p_0402"
			(at -1.022927 2.155213 0)
			(layer "F.Fab")
			(effects
				(font
					(size 0.7 0.7)
					(thickness 0.15)
				)
				(justify right bottom)
			)
		)
		(property "Datasheet" "https://product.samsungsem.com/mlcc/CL05C180JB51PN.do"
			(at 0 0 180)
			(layer "F.Fab")
			(hide yes)
			(effects
				(font
					(size 1.27 1.27)
					(thickness 0.15)
				)
			)
		)
		(property "MPN" "CL05C180JB51PNC"
			(at 0 0 180)
			(unlocked yes)
			(layer "F.Fab")
			(hide yes)
			(effects
				(font
					(size 1 1)
					(thickness 0.15)
				)
			)
		)
		(property "Manufacturer" "Samsung Electro-Mechanics"
			(at 0 0 180)
			(unlocked yes)
			(layer "F.Fab")
			(hide yes)
			(effects
				(font
					(size 1 1)
					(thickness 0.15)
				)
			)
		)
		(property "License" "Apache-2.0"
			(at 0 0 180)
			(unlocked yes)
			(layer "F.Fab")
			(hide yes)
			(effects
				(font
					(size 1 1)
					(thickness 0.15)
				)
			)
		)
		(property "Author" "Antmicro"
			(at 0 0 180)
			(unlocked yes)
			(layer "F.Fab")
			(hide yes)
			(effects
				(font
					(size 1 1)
					(thickness 0.15)
				)
			)
		)
		(property "Val" "18p"
			(at 0 0 180)
			(unlocked yes)
			(layer "F.Fab")
			(hide yes)
			(effects
				(font
					(size 1 1)
					(thickness 0.15)
				)
			)
		)
		(property "Voltage" ""
			(at 0 0 180)
			(unlocked yes)
			(layer "F.Fab")
			(hide yes)
			(effects
				(font
					(size 1 1)
					(thickness 0.15)
				)
			)
		)
		(property "Dielectric" ""
			(at 0 0 180)
			(unlocked yes)
			(layer "F.Fab")
			(hide yes)
			(effects
				(font
					(size 1 1)
					(thickness 0.15)
				)
			)
		)
		(sheetname "/Ethernet/")
		(sheetfile "ethernet.kicad_sch")
		(attr smd)
		(fp_rect
			(start -0.925 -0.47)
			(end 0.925 0.47)
			(stroke
				(width 0.05)
				(type default)
			)
			(fill no)
			(layer "F.CrtYd")
		)
		(fp_line
			(start 0.504 0.248)
			(end -0.494 0.248)
			(stroke
				(width 0.15)
				(type solid)
			)
			(layer "F.Fab")
		)
		(fp_line
			(start 0.504 -0.25)
			(end 0.504 0.248)
			(stroke
				(width 0.15)
				(type solid)
			)
			(layer "F.Fab")
		)
		(fp_line
			(start -0.494 0.248)
			(end -0.494 -0.25)
			(stroke
				(width 0.15)
				(type solid)
			)
			(layer "F.Fab")
		)
		(fp_line
			(start -0.494 -0.25)
			(end 0.504 -0.25)
			(stroke
				(width 0.15)
				(type solid)
			)
			(layer "F.Fab")
		)
		(fp_text user "Author: Antmicro"
			(at -0.939 3.399 180)
			(layer "F.Fab")
			(effects
				(font
					(size 0.7 0.7)
					(thickness 0.15)
				)
				(justify left bottom)
			)
		)
		(fp_text user "${REFERENCE}"
			(at -0.939 4.599 180)
			(layer "F.Fab")
			(effects
				(font
					(size 0.7 0.7)
					(thickness 0.15)
				)
				(justify left bottom)
			)
		)
		(fp_text user "License: Apache-2.0"
			(at -0.939 5.799 180)
			(layer "F.Fab")
			(effects
				(font
					(size 0.7 0.7)
					(thickness 0.15)
				)
				(justify left bottom)
			)
		)
		(pad "1" smd roundrect
			(at -0.48 0 180)
			(size 0.59 0.64)
			(layers "F.Cu" "F.Mask" "F.Paste")
			(roundrect_rratio 0.25)
			(net 1 "GND")
			(pintype "passive")
		)
		(pad "2" smd roundrect
			(at 0.48 0 180)
			(size 0.59 0.64)
			(layers "F.Cu" "F.Mask" "F.Paste")
			(roundrect_rratio 0.25)
			(net 228 "Net-(U15-XO)")
			(pintype "passive")
		)
	)
	(footprint "antmicro-footprints:C_0402_1005Metric"
		(layer "F.Cu")
		(at 145.125 138.607851)
		(descr "Capacitor SMD 0402")
		(tags "capacitor SMD 0402")
		(property "Reference" "C162"
			(at 0 -0.699 0)
			(layer "F.SilkS")
			(effects
				(font
					(size 0.7 0.7)
					(thickness 0.15)
				)
				(justify left bottom)
			)
		)
		(property "Value" "C_18p_0402"
			(at -1.022927 2.155213 0)
			(layer "F.Fab")
			(effects
				(font
					(size 0.7 0.7)
					(thickness 0.15)
				)
				(justify left bottom)
			)
		)
		(property "Datasheet" "https://product.samsungsem.com/mlcc/CL05C180JB51PN.do"
			(at 0 0 0)
			(layer "F.Fab")
			(hide yes)
			(effects
				(font
					(size 1.27 1.27)
					(thickness 0.15)
				)
			)
		)
		(property "MPN" "CL05C180JB51PNC"
			(at 0 0 0)
			(unlocked yes)
			(layer "F.Fab")
			(hide yes)
			(effects
				(font
					(size 1 1)
					(thickness 0.15)
				)
			)
		)
		(property "Manufacturer" "Samsung Electro-Mechanics"
			(at 0 0 0)
			(unlocked yes)
			(layer "F.Fab")
			(hide yes)
			(effects
				(font
					(size 1 1)
					(thickness 0.15)
				)
			)
		)
		(property "License" "Apache-2.0"
			(at 0 0 0)
			(unlocked yes)
			(layer "F.Fab")
			(hide yes)
			(effects
				(font
					(size 1 1)
					(thickness 0.15)
				)
			)
		)
		(property "Author" "Antmicro"
			(at 0 0 0)
			(unlocked yes)
			(layer "F.Fab")
			(hide yes)
			(effects
				(font
					(size 1 1)
					(thickness 0.15)
				)
			)
		)
		(property "Val" "18p"
			(at 0 0 0)
			(unlocked yes)
			(layer "F.Fab")
			(hide yes)
			(effects
				(font
					(size 1 1)
					(thickness 0.15)
				)
			)
		)
		(property "Voltage" ""
			(at 0 0 0)
			(unlocked yes)
			(layer "F.Fab")
			(hide yes)
			(effects
				(font
					(size 1 1)
					(thickness 0.15)
				)
			)
		)
		(property "Dielectric" ""
			(at 0 0 0)
			(unlocked yes)
			(layer "F.Fab")
			(hide yes)
			(effects
				(font
					(size 1 1)
					(thickness 0.15)
				)
			)
		)
		(sheetname "/Ethernet/")
		(sheetfile "ethernet.kicad_sch")
		(attr smd)
		(fp_rect
			(start -0.925 -0.47)
			(end 0.925 0.47)
			(stroke
				(width 0.05)
				(type default)
			)
			(fill no)
			(layer "F.CrtYd")
		)
		(fp_line
			(start -0.494 -0.25)
			(end 0.504 -0.25)
			(stroke
				(width 0.15)
				(type solid)
			)
			(layer "F.Fab")
		)
		(fp_line
			(start -0.494 0.248)
			(end -0.494 -0.25)
			(stroke
				(width 0.15)
				(type solid)
			)
			(layer "F.Fab")
		)
		(fp_line
			(start 0.504 -0.25)
			(end 0.504 0.248)
			(stroke
				(width 0.15)
				(type solid)
			)
			(layer "F.Fab")
		)
		(fp_line
			(start 0.504 0.248)
			(end -0.494 0.248)
			(stroke
				(width 0.15)
				(type solid)
			)
			(layer "F.Fab")
		)
		(fp_text user "${REFERENCE}"
			(at -0.939 4.599 0)
			(layer "F.Fab")
			(effects
				(font
					(size 0.7 0.7)
					(thickness 0.15)
				)
				(justify left bottom)
			)
		)
		(fp_text user "License: Apache-2.0"
			(at -0.939 5.799 0)
			(layer "F.Fab")
			(effects
				(font
					(size 0.7 0.7)
					(thickness 0.15)
				)
				(justify left bottom)
			)
		)
		(fp_text user "Author: Antmicro"
			(at -0.939 3.399 0)
			(layer "F.Fab")
			(effects
				(font
					(size 0.7 0.7)
					(thickness 0.15)
				)
				(justify left bottom)
			)
		)
		(pad "1" smd roundrect
			(at -0.48 0)
			(size 0.59 0.64)
			(layers "F.Cu" "F.Mask" "F.Paste")
			(roundrect_rratio 0.25)
			(net 1 "GND")
			(pintype "passive")
		)
		(pad "2" smd roundrect
			(at 0.48 0)
			(size 0.59 0.64)
			(layers "F.Cu" "F.Mask" "F.Paste")
			(roundrect_rratio 0.25)
			(net 227 "Net-(U15-XI)")
			(pintype "passive")
		)
	)
	(footprint "antmicro-footprints:FB_0603_1608Metric"
		(layer "F.Cu")
		(at 145.625 144.672149 180)
		(property "Reference" "FB6"
			(at -3.35 -0.602851 0)
			(layer "F.SilkS")
			(effects
				(font
					(size 0.7 0.7)
					(thickness 0.15)
				)
				(justify right bottom)
			)
		)
		(property "Value" "FB_120Z_2A_Murata-BLM18PG_0603"
			(at 0 1.5 0)
			(layer "F.Fab")
			(effects
				(font
					(size 0.7 0.7)
					(thickness 0.15)
				)
				(justify right bottom)
			)
		)
		(property "Datasheet" "https://www.murata.com/en-us/products/productdata/8796738650142/ENFA0003.pdf"
			(at 0 0 180)
			(layer "F.Fab")
			(hide yes)
			(effects
				(font
					(size 1.27 1.27)
					(thickness 0.15)
				)
			)
		)
		(property "Val" "120Z/2A"
			(at 0 0 180)
			(unlocked yes)
			(layer "F.Fab")
			(hide yes)
			(effects
				(font
					(size 1 1)
					(thickness 0.15)
				)
			)
		)
		(property "MPN" "BLM18PG121SN1D"
			(at 0 0 180)
			(unlocked yes)
			(layer "F.Fab")
			(hide yes)
			(effects
				(font
					(size 1 1)
					(thickness 0.15)
				)
			)
		)
		(property "Manufacturer" "Murata"
			(at 0 0 180)
			(unlocked yes)
			(layer "F.Fab")
			(hide yes)
			(effects
				(font
					(size 1 1)
					(thickness 0.15)
				)
			)
		)
		(property "Author" "Antmicro"
			(at 0 0 180)
			(unlocked yes)
			(layer "F.Fab")
			(hide yes)
			(effects
				(font
					(size 1 1)
					(thickness 0.15)
				)
			)
		)
		(property "License" "Apache-2.0"
			(at 0 0 180)
			(unlocked yes)
			(layer "F.Fab")
			(hide yes)
			(effects
				(font
					(size 1 1)
					(thickness 0.15)
				)
			)
		)
		(sheetname "/Ethernet/")
		(sheetfile "ethernet.kicad_sch")
		(attr smd)
		(fp_line
			(start -0.15 0.4)
			(end 0.15 0.4)
			(stroke
				(width 0.15)
				(type solid)
			)
			(layer "F.SilkS")
		)
		(fp_line
			(start -0.15 -0.4)
			(end 0.15 -0.4)
			(stroke
				(width 0.15)
				(type solid)
			)
			(layer "F.SilkS")
		)
		(fp_rect
			(start -1.25 -0.65)
			(end 1.25 0.65)
			(stroke
				(width 0.05)
				(type solid)
			)
			(fill no)
			(layer "F.CrtYd")
		)
		(fp_line
			(start 0.8 0.406)
			(end -0.803 0.406)
			(stroke
				(width 0.15)
				(type solid)
			)
			(layer "F.Fab")
		)
		(fp_line
			(start 0.8 -0.408)
			(end 0.8 0.406)
			(stroke
				(width 0.15)
				(type solid)
			)
			(layer "F.Fab")
		)
		(fp_line
			(start 0.8 -0.408)
			(end -0.803 -0.408)
			(stroke
				(width 0.15)
				(type solid)
			)
			(layer "F.Fab")
		)
		(fp_line
			(start -0.803 0.406)
			(end -0.803 -0.408)
			(stroke
				(width 0.15)
				(type solid)
			)
			(layer "F.Fab")
		)
		(fp_text user "License: Apache-2.0"
			(at -1.653 5.9 180)
			(layer "F.Fab")
			(effects
				(font
					(size 0.7 0.7)
					(thickness 0.15)
				)
				(justify left bottom)
			)
		)
		(fp_text user "${REFERENCE}"
			(at -1.653 4.6 180)
			(layer "F.Fab")
			(effects
				(font
					(size 0.7 0.7)
					(thickness 0.15)
				)
				(justify left bottom)
			)
		)
		(fp_text user "Author: Antmicro"
			(at -1.653 3.162 180)
			(layer "F.Fab")
			(effects
				(font
					(size 0.7 0.7)
					(thickness 0.15)
				)
				(justify left bottom)
			)
		)
		(pad "1" smd roundrect
			(at -0.7 0 180)
			(size 0.8 1)
			(layers "F.Cu" "F.Mask" "F.Paste")
			(roundrect_rratio 0.2)
			(net 150 "+1V2")
			(pintype "passive")
		)
		(pad "2" smd roundrect
			(at 0.7 0 180)
			(size 0.8 1)
			(layers "F.Cu" "F.Mask" "F.Paste")
			(roundrect_rratio 0.2)
			(net 96 "/Ethernet/AVDDL_PLL")
			(pintype "passive")
		)
	)
)
